# S9S_MB_2U (Grand Teton) — schematic netlist excerpt (pin names and nets, part order shuffled) for the footprints in the layout excerpt that follows; sources: Cadence DE-HDL packaged netlist, KiCad conversion of 03242023_DA0F0TMBIJ0_F0T_Motherboard_J_brd_V01_OCP.brd

R3903  Q_RES  49.9 1% CHIP  pkg 0402LF  page 110 : A = I3C_SPD_DDREFGH_CPU1_LVC1_SCL_4 ; B = I3C_SPD_DDREFGH_CPU1_LVC1_SCL
R1419  Q_RES  2K 1% CHIP  pkg 0402LF  page 219 : A = RST_PCIE_PCH_DEV_PERST_N ; B = GND
C73  Q_CAP  10UF 16V 10% X6S  pkg C0805  page 113 : A = P12V_S3_AUX_CPU1_NVDIMM ; B = GND

(kicad_pcb
	(version 20260206)
	(generator "pcbnew")
	(generator_version "10.0")
	(general
		(thickness 1.6)
		(legacy_teardrops no)
	)
	(paper "A4")
	(title_block
		(title "03242023_DA0F0TMBIJ0_F0T_Motherboard_J_brd_V01_OCP.brd")
		(comment 1 "Grand Teton / footprints 4851-4853 of 6105")
	)
	(layers
		(0 "F.Cu" signal "TOP")
		(4 "In1.Cu" signal "GND")
		(6 "In2.Cu" signal "IN1")
		(8 "In3.Cu" signal "GND1")
		(10 "In4.Cu" signal "IN2")
		(12 "In5.Cu" signal "GND2")
		(14 "In6.Cu" signal "IN3")
		(16 "In7.Cu" signal "GND3")
		(18 "In8.Cu" signal "VCC")
		(20 "In9.Cu" signal "VCC1")
		(22 "In10.Cu" signal "GND4")
		(24 "In11.Cu" signal "IN4")
		(26 "In12.Cu" signal "GND5")
		(28 "In13.Cu" signal "IN5")
		(30 "In14.Cu" signal "GND6")
		(32 "In15.Cu" signal "IN6")
		(34 "In16.Cu" signal "GND7")
		(2 "B.Cu" signal "BOTTOM")
		(9 "F.Adhes" user "F.Adhesive")
		(11 "B.Adhes" user "B.Adhesive")
		(13 "F.Paste" user "Package Geometry/Pastemask Top")
		(15 "B.Paste" user "Package Geometry/Pastemask Bottom")
		(5 "F.SilkS" user "Ref Des/Silkscreen Top")
		(7 "B.SilkS" user "Ref Des/Silkscreen Bottom")
		(1 "F.Mask" user "Board Geometry/Soldermask Top")
		(3 "B.Mask" user "Board Geometry/Soldermask Bottom")
		(17 "Dwgs.User" user "User.Drawings")
		(19 "Cmts.User" user "User.Comments")
		(21 "Eco1.User" user "User.Eco1")
		(23 "Eco2.User" user "User.Eco2")
		(25 "Edge.Cuts" user "Board Geometry/Outline")
		(27 "Margin" user)
		(31 "F.CrtYd" user "Package Geometry/Place Bound Top")
		(29 "B.CrtYd" user "Package Geometry/Place Bound Bottom")
		(35 "F.Fab" user "Ref Des/Assembly Top")
		(33 "B.Fab" user "Ref Des/Assembly Bottom")
	)
	(footprint ""
		(layer "B.Cu")
		(at 193.38036 -118.074948 180)
		(property "Reference" "R1419"
			(at 0 0 0)
			(layer "B.SilkS")
			(hide yes)
			(effects
				(font
					(size 1.27 1.27)
				)
				(justify mirror)
			)
		)
		(property "Value" ""
			(at 0 0 0)
			(layer "B.Fab")
			(effects
				(font
					(size 1.27 1.27)
				)
				(justify mirror)
			)
		)
		(duplicate_pad_numbers_are_jumpers no)
		(fp_line
			(start 0.7874 0.4064)
			(end 0.7874 -0.4064)
			(stroke
				(width 0.1524)
				(type default)
			)
			(layer "B.SilkS")
		)
		(fp_line
			(start 0.7874 -0.4064)
			(end -0.7874 -0.4064)
			(stroke
				(width 0.1524)
				(type default)
			)
			(layer "B.SilkS")
		)
		(fp_line
			(start -0.7874 0.4064)
			(end 0.7874 0.4064)
			(stroke
				(width 0.1524)
				(type default)
			)
			(layer "B.SilkS")
		)
		(fp_line
			(start -0.7874 -0.4064)
			(end -0.7874 0.4064)
			(stroke
				(width 0.1524)
				(type default)
			)
			(layer "B.SilkS")
		)
		(fp_line
			(start 0.67945 0.3048)
			(end 0.67945 -0.305054)
			(stroke
				(width 0.1)
				(type default)
			)
			(layer "B.Fab")
		)
		(fp_line
			(start 0.67945 -0.305054)
			(end 0.12065 -0.305054)
			(stroke
				(width 0.1)
				(type default)
			)
			(layer "B.Fab")
		)
		(fp_line
			(start 0.12065 0.3048)
			(end 0.67945 0.3048)
			(stroke
				(width 0.1)
				(type default)
			)
			(layer "B.Fab")
		)
		(fp_line
			(start 0.12065 0.2794)
			(end 0.12065 0.3048)
			(stroke
				(width 0.1)
				(type default)
			)
			(layer "B.Fab")
		)
		(fp_line
			(start 0.12065 -0.2794)
			(end -0.12065 -0.2794)
			(stroke
				(width 0.1)
				(type default)
			)
			(layer "B.Fab")
		)
		(fp_line
			(start 0.12065 -0.305054)
			(end 0.12065 -0.2794)
			(stroke
				(width 0.1)
				(type default)
			)
			(layer "B.Fab")
		)
		(fp_line
			(start -0.120396 0.3048)
			(end -0.120396 0.2794)
			(stroke
				(width 0.1)
				(type default)
			)
			(layer "B.Fab")
		)
		(fp_line
			(start -0.120396 0.2794)
			(end 0.12065 0.2794)
			(stroke
				(width 0.1)
				(type default)
			)
			(layer "B.Fab")
		)
		(fp_line
			(start -0.12065 -0.2794)
			(end -0.12065 -0.3048)
			(stroke
				(width 0.1)
				(type default)
			)
			(layer "B.Fab")
		)
		(fp_line
			(start -0.12065 -0.3048)
			(end -0.67945 -0.3048)
			(stroke
				(width 0.1)
				(type default)
			)
			(layer "B.Fab")
		)
		(fp_line
			(start -0.67945 0.3048)
			(end -0.120396 0.3048)
			(stroke
				(width 0.1)
				(type default)
			)
			(layer "B.Fab")
		)
		(fp_line
			(start -0.67945 -0.3048)
			(end -0.67945 0.3048)
			(stroke
				(width 0.1)
				(type default)
			)
			(layer "B.Fab")
		)
		(pad "1" smd circle
			(at 0.40005 0)
			(size 0 0)
			(layers "B.Cu" "B.Mask" "B.Paste")
			(net "RST_PCIE_PCH_DEV_PERST_N")
		)
		(pad "2" smd circle
			(at -0.40005 0)
			(size 0 0)
			(layers "B.Cu" "B.Mask" "B.Paste")
			(net "GND")
		)
	)
	(footprint ""
		(layer "B.Cu")
		(at 208.152746 -321.554856 -90)
		(property "Reference" "C73"
			(at 0 0 90)
			(layer "B.SilkS")
			(hide yes)
			(effects
				(font
					(size 1.27 1.27)
				)
				(justify mirror)
			)
		)
		(property "Value" ""
			(at 0 0 90)
			(layer "B.Fab")
			(effects
				(font
					(size 1.27 1.27)
				)
				(justify mirror)
			)
		)
		(duplicate_pad_numbers_are_jumpers no)
		(fp_line
			(start -1.524 0.762)
			(end 1.524 0.762)
			(stroke
				(width 0.1524)
				(type default)
			)
			(layer "B.SilkS")
		)
		(fp_line
			(start 1.524 0.762)
			(end 1.524 -0.762)
			(stroke
				(width 0.1524)
				(type default)
			)
			(layer "B.SilkS")
		)
		(fp_line
			(start -1.524 -0.762)
			(end -1.524 0.762)
			(stroke
				(width 0.1524)
				(type default)
			)
			(layer "B.SilkS")
		)
		(fp_line
			(start 1.524 -0.762)
			(end -1.524 -0.762)
			(stroke
				(width 0.1524)
				(type default)
			)
			(layer "B.SilkS")
		)
		(fp_line
			(start -1.1049 0.724916)
			(end -1.1049 -0.724916)
			(stroke
				(width 0.1)
				(type default)
			)
			(layer "B.Fab")
		)
		(fp_line
			(start 1.1049 0.724916)
			(end -1.1049 0.724916)
			(stroke
				(width 0.1)
				(type default)
			)
			(layer "B.Fab")
		)
		(fp_line
			(start -1.1049 -0.724916)
			(end 1.1049 -0.724916)
			(stroke
				(width 0.1)
				(type default)
			)
			(layer "B.Fab")
		)
		(fp_line
			(start 1.1049 -0.724916)
			(end 1.1049 0.724916)
			(stroke
				(width 0.1)
				(type default)
			)
			(layer "B.Fab")
		)
		(pad "1" smd rect
			(at 0.889 0 270)
			(size 1.016 1.27)
			(layers "B.Cu" "B.Mask" "B.Paste")
			(net "P12V_S3_AUX_CPU1_NVDIMM")
		)
		(pad "2" smd rect
			(at -0.889 0 270)
			(size 1.016 1.27)
			(layers "B.Cu" "B.Mask" "B.Paste")
			(net "GND")
		)
	)
	(footprint ""
		(layer "B.Cu")
		(at 196.23278 -316.868048 90)
		(property "Reference" "R3903"
			(at 0 0 90)
			(layer "B.SilkS")
			(hide yes)
			(effects
				(font
					(size 1.27 1.27)
				)
				(justify mirror)
			)
		)
		(property "Value" ""
			(at 0 0 90)
			(layer "B.Fab")
			(effects
				(font
					(size 1.27 1.27)
				)
				(justify mirror)
			)
		)
		(duplicate_pad_numbers_are_jumpers no)
		(fp_line
			(start 0.7874 -0.4064)
			(end -0.7874 -0.4064)
			(stroke
				(width 0.1524)
				(type default)
			)
			(layer "B.SilkS")
		)
		(fp_line
			(start -0.7874 -0.4064)
			(end -0.7874 0.4064)
			(stroke
				(width 0.1524)
				(type default)
			)
			(layer "B.SilkS")
		)
		(fp_line
			(start 0.7874 0.4064)
			(end 0.7874 -0.4064)
			(stroke
				(width 0.1524)
				(type default)
			)
			(layer "B.SilkS")
		)
		(fp_line
			(start -0.7874 0.4064)
			(end 0.7874 0.4064)
			(stroke
				(width 0.1524)
				(type default)
			)
			(layer "B.SilkS")
		)
		(fp_line
			(start 0.67945 -0.305054)
			(end 0.12065 -0.305054)
			(stroke
				(width 0.1)
				(type default)
			)
			(layer "B.Fab")
		)
		(fp_line
			(start 0.12065 -0.305054)
			(end 0.12065 -0.2794)
			(stroke
				(width 0.1)
				(type default)
			)
			(layer "B.Fab")
		)
		(fp_line
			(start -0.12065 -0.3048)
			(end -0.67945 -0.3048)
			(stroke
				(width 0.1)
				(type default)
			)
			(layer "B.Fab")
		)
		(fp_line
			(start -0.67945 -0.3048)
			(end -0.67945 0.3048)
			(stroke
				(width 0.1)
				(type default)
			)
			(layer "B.Fab")
		)
		(fp_line
			(start 0.12065 -0.2794)
			(end -0.12065 -0.2794)
			(stroke
				(width 0.1)
				(type default)
			)
			(layer "B.Fab")
		)
		(fp_line
			(start -0.12065 -0.2794)
			(end -0.12065 -0.3048)
			(stroke
				(width 0.1)
				(type default)
			)
			(layer "B.Fab")
		)
		(fp_line
			(start 0.12065 0.2794)
			(end 0.12065 0.3048)
			(stroke
				(width 0.1)
				(type default)
			)
			(layer "B.Fab")
		)
		(fp_line
			(start -0.120396 0.2794)
			(end 0.12065 0.2794)
			(stroke
				(width 0.1)
				(type default)
			)
			(layer "B.Fab")
		)
		(fp_line
			(start 0.67945 0.3048)
			(end 0.67945 -0.305054)
			(stroke
				(width 0.1)
				(type default)
			)
			(layer "B.Fab")
		)
		(fp_line
			(start 0.12065 0.3048)
			(end 0.67945 0.3048)
			(stroke
				(width 0.1)
				(type default)
			)
			(layer "B.Fab")
		)
		(fp_line
			(start -0.120396 0.3048)
			(end -0.120396 0.2794)
			(stroke
				(width 0.1)
				(type default)
			)
			(layer "B.Fab")
		)
		(fp_line
			(start -0.67945 0.3048)
			(end -0.120396 0.3048)
			(stroke
				(width 0.1)
				(type default)
			)
			(layer "B.Fab")
		)
		(pad "1" smd circle
			(at 0.40005 0 270)
			(size 0 0)
			(layers "B.Cu" "B.Mask" "B.Paste")
			(net "I3C_SPD_DDREFGH_CPU1_LVC1_SCL_4")
		)
		(pad "2" smd circle
			(at -0.40005 0 270)
			(size 0 0)
			(layers "B.Cu" "B.Mask" "B.Paste")
			(net "I3C_SPD_DDREFGH_CPU1_LVC1_SCL")
		)
	)
)
